# TIMECARD (Time Appliance Project (Time Card)) — schematic netlist excerpt (pin names and nets, part order shuffled) for the footprints in the layout excerpt that follows; sources: Cadence DE-HDL packaged netlist, KiCad conversion of R4006-B0001-02_R01.brd

C276  CAPACITOR  0.1UF 25V 10%  pkg SMC_0402R_H022  page 19 : \1\ = XP1R8V_FPGA ; \2\ = SG
R456  RESISTOR  100OHM 1%  pkg SMC_0402R_H016  page 24 : \1\ = XP3R3V_FT_PG ; \2\ = FT_USB_DETECT

(kicad_pcb
	(version 20260206)
	(generator "pcbnew")
	(generator_version "10.0")
	(general
		(thickness 1.6)
		(legacy_teardrops no)
	)
	(paper "A4")
	(title_block
		(title "timecard-production-celestica-r4006 — R4006-B0001-02_R01.brd")
		(comment 1 "Time Appliance Project (Time Card) / footprints 38-39 of 1113")
	)
	(layers
		(0 "F.Cu" signal "TOP")
		(4 "In1.Cu" signal "L02_GND1")
		(6 "In2.Cu" signal "L03_SIG1")
		(8 "In3.Cu" signal "L04_GND2")
		(10 "In4.Cu" signal "L05_VCC1")
		(12 "In5.Cu" signal "L06_VCC2")
		(14 "In6.Cu" signal "L07_GND3")
		(16 "In7.Cu" signal "L08_SIG2")
		(18 "In8.Cu" signal "L09_GND4")
		(2 "B.Cu" signal "BOTTOM")
		(9 "F.Adhes" user "F.Adhesive")
		(11 "B.Adhes" user "B.Adhesive")
		(13 "F.Paste" user "Package Geometry/Pastemask Top")
		(15 "B.Paste" user "Package Geometry/Pastemask Bottom")
		(5 "F.SilkS" user "Ref Des/Silkscreen Top")
		(7 "B.SilkS" user "Ref Des/Silkscreen Bottom")
		(1 "F.Mask" user "Board Geometry/Soldermask Top")
		(3 "B.Mask" user "Board Geometry/Soldermask Bottom")
		(17 "Dwgs.User" user "User.Drawings")
		(19 "Cmts.User" user "User.Comments")
		(21 "Eco1.User" user "User.Eco1")
		(23 "Eco2.User" user "User.Eco2")
		(25 "Edge.Cuts" user "Board Geometry/Outline")
		(27 "Margin" user)
		(31 "F.CrtYd" user "Package Geometry/Place Bound Top")
		(29 "B.CrtYd" user "Package Geometry/Place Bound Bottom")
		(35 "F.Fab" user "Ref Des/Assembly Top")
		(33 "B.Fab" user "Ref Des/Assembly Bottom")
	)
	(footprint ""
		(layer "F.Cu")
		(at 26.797 -94.234 -90)
		(property "Reference" "R456"
			(at -4.953 0.34163 90)
			(unlocked yes)
			(layer "F.SilkS")
			(effects
				(font
					(size 0.7874 0.5842)
					(thickness 0.1524)
				)
			)
		)
		(property "Value" "VAL*"
			(at 0.02032 2.13233 270)
			(unlocked yes)
			(layer "F.Fab")
			(hide yes)
			(effects
				(font
					(size 0.7874 0.5842)
					(thickness 0.1524)
				)
			)
		)
		(property "Tolerance" "TOL*"
			(at 0.044704 3.05435 270)
			(unlocked yes)
			(layer "Cmts.User")
			(hide yes)
			(effects
				(font
					(size 0.7874 0.5842)
					(thickness 0.1524)
				)
			)
		)
		(property "User Part Number" "PARTNUM*"
			(at 0.02032 4.024884 270)
			(unlocked yes)
			(layer "Cmts.User")
			(hide yes)
			(effects
				(font
					(size 0.7874 0.5842)
					(thickness 0.1524)
				)
			)
		)
		(property "Device Type" "RESISTOR-G155-11000-01,100OHM,A"
			(at 0.008382 1.210564 270)
			(unlocked yes)
			(layer "F.Fab")
			(hide yes)
			(effects
				(font
					(size 0.7874 0.5842)
					(thickness 0.1524)
				)
			)
		)
		(duplicate_pad_numbers_are_jumpers no)
		(fp_line
			(start -1.143 0.5588)
			(end 1.143 0.5588)
			(stroke
				(width 0.1)
				(type default)
			)
			(layer "F.SilkS")
		)
		(fp_line
			(start 1.143 0.5588)
			(end 1.143 -0.5588)
			(stroke
				(width 0.1)
				(type default)
			)
			(layer "F.SilkS")
		)
		(fp_line
			(start -1.143 -0.5588)
			(end -1.143 0.5588)
			(stroke
				(width 0.1)
				(type default)
			)
			(layer "F.SilkS")
		)
		(fp_line
			(start 1.143 -0.5588)
			(end -1.143 -0.5588)
			(stroke
				(width 0.1)
				(type default)
			)
			(layer "F.SilkS")
		)
		(fp_poly
			(pts
				(xy -1.143 0.5588) (xy 1.143 0.5588) (xy 1.143 -0.5588) (xy -1.143 -0.5588)
			)
			(stroke
				(width 0)
				(type default)
			)
			(fill no)
			(layer "F.CrtYd")
		)
		(fp_line
			(start -0.508 0.3048)
			(end 0.508 0.3048)
			(stroke
				(width 0.1)
				(type default)
			)
			(layer "F.Fab")
		)
		(fp_line
			(start 0.508 0.3048)
			(end 0.508 -0.3048)
			(stroke
				(width 0.1)
				(type default)
			)
			(layer "F.Fab")
		)
		(fp_line
			(start -0.508 -0.3048)
			(end -0.508 0.3048)
			(stroke
				(width 0.1)
				(type default)
			)
			(layer "F.Fab")
		)
		(fp_line
			(start 0.508 -0.3048)
			(end -0.508 -0.3048)
			(stroke
				(width 0.1)
				(type default)
			)
			(layer "F.Fab")
		)
		(pad "1" smd rect
			(at -0.5334 0 270)
			(size 0.7112 0.6096)
			(layers "F.Cu" "F.Mask" "F.Paste")
			(net "XP3R3V_FT_PG")
		)
		(pad "2" smd rect
			(at 0.5334 0 270)
			(size 0.7112 0.6096)
			(layers "F.Cu" "F.Mask" "F.Paste")
			(net "FT_USB_DETECT")
		)
		(zone
			(layer "F.Cu")
			(hatch none 0.5)
			(connect_pads
				(clearance 0)
			)
			(min_thickness 0.25)
			(keepout
				(tracks allowed)
				(vias not_allowed)
				(pads allowed)
				(copperpour not_allowed)
				(footprints allowed)
			)
			(placement
				(enabled no)
				(sheetname "")
			)
			(fill
				(thermal_gap 0.5)
				(thermal_bridge_width 0.5)
				(island_removal_mode 0)
			)
			(polygon
				(pts
					(xy 26.4922 -94.3102) (xy 26.4922 -94.1578) (xy 27.1018 -94.1578) (xy 27.1018 -94.3102)
				)
			)
		)
		(zone
			(layer "F.Cu")
			(hatch none 0.5)
			(connect_pads
				(clearance 0)
			)
			(min_thickness 0.25)
			(keepout
				(tracks not_allowed)
				(vias allowed)
				(pads allowed)
				(copperpour not_allowed)
				(footprints allowed)
			)
			(placement
				(enabled no)
				(sheetname "")
			)
			(fill
				(thermal_gap 0.5)
				(thermal_bridge_width 0.5)
				(island_removal_mode 0)
			)
			(polygon
				(pts
					(xy 26.4922 -94.3102) (xy 26.4922 -94.1578) (xy 27.1018 -94.1578) (xy 27.1018 -94.3102)
				)
			)
		)
	)
	(footprint ""
		(layer "F.Cu")
		(at 23.5712 -65.544192 180)
		(property "Reference" "C276"
			(at -3.4798 -0.051562 0)
			(unlocked yes)
			(layer "F.SilkS")
			(effects
				(font
					(size 0.7874 0.5842)
					(thickness 0.1524)
				)
			)
		)
		(property "Value" "VAL*"
			(at 0.0762 2.067306 180)
			(unlocked yes)
			(layer "F.Fab")
			(hide yes)
			(effects
				(font
					(size 0.7874 0.5842)
					(thickness 0.1524)
				)
			)
		)
		(property "Tolerance" "TOL*"
			(at 0.0762 3.032506 180)
			(unlocked yes)
			(layer "Cmts.User")
			(hide yes)
			(effects
				(font
					(size 0.7874 0.5842)
					(thickness 0.1524)
				)
			)
		)
		(property "User Part Number" "PARTNUM*"
			(at 0.1016 4.023106 180)
			(unlocked yes)
			(layer "Cmts.User")
			(hide yes)
			(effects
				(font
					(size 0.7874 0.5842)
					(thickness 0.1524)
				)
			)
		)
		(property "Device Type" "CAPACITOR-G105-0B104-EK,0.1UF,A"
			(at 0.0508 1.127506 180)
			(unlocked yes)
			(layer "F.Fab")
			(hide yes)
			(effects
				(font
					(size 0.7874 0.5842)
					(thickness 0.1524)
				)
			)
		)
		(duplicate_pad_numbers_are_jumpers no)
		(fp_line
			(start 1.143 0.5588)
			(end 1.143 -0.5588)
			(stroke
				(width 0.1)
				(type default)
			)
			(layer "F.SilkS")
		)
		(fp_line
			(start 1.143 -0.5588)
			(end -1.143 -0.5588)
			(stroke
				(width 0.1)
				(type default)
			)
			(layer "F.SilkS")
		)
		(fp_line
			(start -1.143 0.5588)
			(end 1.143 0.5588)
			(stroke
				(width 0.1)
				(type default)
			)
			(layer "F.SilkS")
		)
		(fp_line
			(start -1.143 -0.5588)
			(end -1.143 0.5588)
			(stroke
				(width 0.1)
				(type default)
			)
			(layer "F.SilkS")
		)
		(fp_rect
			(start 1.143 0.5588)
			(end -1.143 -0.5588)
			(stroke
				(width 0)
				(type default)
			)
			(fill no)
			(layer "F.CrtYd")
		)
		(fp_line
			(start 0.508 0.3048)
			(end 0.508 -0.3048)
			(stroke
				(width 0.1)
				(type default)
			)
			(layer "F.Fab")
		)
		(fp_line
			(start 0.508 -0.3048)
			(end -0.508 -0.3048)
			(stroke
				(width 0.1)
				(type default)
			)
			(layer "F.Fab")
		)
		(fp_line
			(start -0.508 0.3048)
			(end 0.508 0.3048)
			(stroke
				(width 0.1)
				(type default)
			)
			(layer "F.Fab")
		)
		(fp_line
			(start -0.508 -0.3048)
			(end -0.508 0.3048)
			(stroke
				(width 0.1)
				(type default)
			)
			(layer "F.Fab")
		)
		(pad "1" smd rect
			(at -0.5334 0 180)
			(size 0.7112 0.6096)
			(layers "F.Cu" "F.Mask" "F.Paste")
			(net "XP1R8V_FPGA")
		)
		(pad "2" smd rect
			(at 0.5334 0 180)
			(size 0.7112 0.6096)
			(layers "F.Cu" "F.Mask" "F.Paste")
			(net "SG")
		)
		(zone
			(layer "F.Cu")
			(hatch none 0.5)
			(connect_pads
				(clearance 0)
			)
			(min_thickness 0.25)
			(keepout
				(tracks allowed)
				(vias not_allowed)
				(pads allowed)
				(copperpour not_allowed)
				(footprints allowed)
			)
			(placement
				(enabled no)
				(sheetname "")
			)
			(fill
				(thermal_gap 0.5)
				(thermal_bridge_width 0.5)
				(island_removal_mode 0)
			)
			(polygon
				(pts
					(xy 23.495 -65.848992) (xy 23.495 -65.239392) (xy 23.6474 -65.239392) (xy 23.6474 -65.848992)
				)
			)
		)
	)
)
